# Antmicro Baseboard for Jetson AGX Thor — KiCad custom design rules (.kicad_dru)
(version 1)

#---------------------- 85 Ohm ----------------------
(rule "(85_ohm_inner"
	(layer inner)
	(condition "(A.NetClass == '85Ohm-diff*')")
	(constraint track_width (opt 0.15mm))
	(constraint diff_pair_gap  (opt 0.125mm))
)
(rule "(85_ohm_outer"
	(layer outer)
	(condition "(A.NetClass == '85Ohm-*')")
	(constraint track_width (opt 0.19mm))
	(constraint diff_pair_gap  (opt 0.18mm))
)

#---------------------- 90 Ohm ----------------------

(rule "(90_ohm_inner"
	(layer inner)
	(condition "(A.NetClass == '90Ohm-diff*')")
	(constraint track_width (opt 0.125mm))
	(constraint diff_pair_gap  (opt 0.10mm))
)
(rule "(90_ohm_outer"
	(layer outer)
	(condition "(A.NetClass == '90Ohm-diff*')")
	(constraint track_width (opt 0.17mm))
	(constraint diff_pair_gap  (opt 0.18mm))
)

#-------------- HS - Zone clearance --------------

(rule "(hs_zone_clearance"
	(condition "(A.NetClass == '*diff*')&&(B.Type == 'Zone')&&(A.Layer == B.Layer)&&(A.NetName != '*USB*')")
	(constraint clearance (min 1mm))
)
